(kicad_pcb
	(version 20260206)
	(generator "pcbnew")
	(generator_version "10.0")
	(general
		(thickness 1.6)
		(legacy_teardrops no)
	)
	(paper "A4")
	(title_block
		(title "Wiwynn_Tioga_Pass_MB.brd")
		(comment 1 "Tioga Pass / footprints 301-308 of 4770")
	)
	(layers
		(0 "F.Cu" signal "TOP")
		(4 "In1.Cu" signal "L2GND")
		(6 "In2.Cu" signal "L3")
		(8 "In3.Cu" signal "L4GND")
		(10 "In4.Cu" signal "L5")
		(12 "In5.Cu" signal "L6GND")
		(14 "In6.Cu" signal "L7VCC")
		(16 "In7.Cu" signal "L8VCC")
		(18 "In8.Cu" signal "L9GND")
		(20 "In9.Cu" signal "L10")
		(22 "In10.Cu" signal "L11GND")
		(24 "In11.Cu" signal "L12")
		(26 "In12.Cu" signal "L13GND")
		(2 "B.Cu" signal "BOTTOM")
		(9 "F.Adhes" user "F.Adhesive")
		(11 "B.Adhes" user "B.Adhesive")
		(13 "F.Paste" user "Package Geometry/Pastemask Top")
		(15 "B.Paste" user "Package Geometry/Pastemask Bottom")
		(5 "F.SilkS" user "Ref Des/Silkscreen Top")
		(7 "B.SilkS" user "Ref Des/Silkscreen Bottom")
		(1 "F.Mask" user "Board Geometry/Soldermask Top")
		(3 "B.Mask" user "Board Geometry/Soldermask Bottom")
		(17 "Dwgs.User" user "User.Drawings")
		(19 "Cmts.User" user "User.Comments")
		(21 "Eco1.User" user "User.Eco1")
		(23 "Eco2.User" user "User.Eco2")
		(25 "Edge.Cuts" user "Board Geometry/Outline")
		(27 "Margin" user)
		(31 "F.CrtYd" user "Package Geometry/Place Bound Top")
		(29 "B.CrtYd" user "Package Geometry/Place Bound Bottom")
		(35 "F.Fab" user "Ref Des/Assembly Top")
		(33 "B.Fab" user "Ref Des/Assembly Bottom")
	)
	(footprint ""
		(layer "F.Cu")
		(at 20.6121 -86.0298 90)
		(property "Reference" "R1D10"
			(at 0 0 90)
			(layer "F.SilkS")
			(hide yes)
			(effects
				(font
					(size 1.27 1.27)
				)
			)
		)
		(property "Value" ""
			(at 0 0 90)
			(layer "F.Fab")
			(effects
				(font
					(size 1.27 1.27)
				)
			)
		)
		(duplicate_pad_numbers_are_jumpers no)
		(fp_poly
			(pts
				(xy -0.2794 -0.1016) (xy 0.2794 -0.1016) (xy 0.2794 0.9906) (xy -0.2794 0.9906)
			)
			(stroke
				(width 0)
				(type default)
			)
			(fill no)
			(layer "F.CrtYd")
		)
		(fp_line
			(start 0.2794 -0.1016)
			(end -0.2794 -0.1016)
			(stroke
				(width 0.1)
				(type default)
			)
			(layer "F.Fab")
		)
		(fp_line
			(start -0.2794 -0.1016)
			(end -0.2794 0.9906)
			(stroke
				(width 0.1)
				(type default)
			)
			(layer "F.Fab")
		)
		(fp_line
			(start 0.2794 0.9906)
			(end 0.2794 -0.1016)
			(stroke
				(width 0.1)
				(type default)
			)
			(layer "F.Fab")
		)
		(fp_line
			(start -0.2794 0.9906)
			(end 0.2794 0.9906)
			(stroke
				(width 0.1)
				(type default)
			)
			(layer "F.Fab")
		)
		(pad "1" smd rect
			(at 0 0 90)
			(size 0.508 0.508)
			(layers "F.Cu" "F.Mask" "F.Paste")
			(net "P3V3_STBY")
		)
		(pad "2" smd rect
			(at 0 0.889 90)
			(size 0.508 0.508)
			(layers "F.Cu" "F.Mask" "F.Paste")
			(net "A_HSC_LOW_GATE")
		)
		(zone
			(layer "F.Cu")
			(hatch none 0.5)
			(connect_pads
				(clearance 0)
			)
			(min_thickness 0.25)
			(keepout
				(tracks allowed)
				(vias not_allowed)
				(pads allowed)
				(copperpour not_allowed)
				(footprints allowed)
			)
			(placement
				(enabled no)
				(sheetname "")
			)
			(fill
				(thermal_gap 0.5)
				(thermal_bridge_width 0.5)
				(island_removal_mode 0)
			)
			(polygon
				(pts
					(xy 20.8661 -85.7758) (xy 20.8661 -86.2838) (xy 21.2471 -86.2838) (xy 21.2471 -85.7758)
				)
			)
		)
		(zone
			(layer "F.Cu")
			(hatch none 0.5)
			(connect_pads
				(clearance 0)
			)
			(min_thickness 0.25)
			(keepout
				(tracks not_allowed)
				(vias allowed)
				(pads allowed)
				(copperpour not_allowed)
				(footprints allowed)
			)
			(placement
				(enabled no)
				(sheetname "")
			)
			(fill
				(thermal_gap 0.5)
				(thermal_bridge_width 0.5)
				(island_removal_mode 0)
			)
			(polygon
				(pts
					(xy 21.2471 -85.7758) (xy 21.2471 -86.2838) (xy 20.8661 -86.2838) (xy 20.8661 -85.7758)
				)
			)
		)
	)
	(footprint ""
		(layer "F.Cu")
		(at 116.3066 -73.025 90)
		(property "Reference" "R3D16"
			(at 0 0 90)
			(layer "F.SilkS")
			(hide yes)
			(effects
				(font
					(size 1.27 1.27)
				)
			)
		)
		(property "Value" ""
			(at 0 0 90)
			(layer "F.Fab")
			(effects
				(font
					(size 1.27 1.27)
				)
			)
		)
		(duplicate_pad_numbers_are_jumpers no)
		(fp_poly
			(pts
				(xy -0.2794 -0.1016) (xy 0.2794 -0.1016) (xy 0.2794 0.9906) (xy -0.2794 0.9906)
			)
			(stroke
				(width 0)
				(type default)
			)
			(fill no)
			(layer "F.CrtYd")
		)
		(fp_line
			(start 0.2794 -0.1016)
			(end -0.2794 -0.1016)
			(stroke
				(width 0.1)
				(type default)
			)
			(layer "F.Fab")
		)
		(fp_line
			(start -0.2794 -0.1016)
			(end -0.2794 0.9906)
			(stroke
				(width 0.1)
				(type default)
			)
			(layer "F.Fab")
		)
		(fp_line
			(start 0.2794 0.9906)
			(end 0.2794 -0.1016)
			(stroke
				(width 0.1)
				(type default)
			)
			(layer "F.Fab")
		)
		(fp_line
			(start -0.2794 0.9906)
			(end 0.2794 0.9906)
			(stroke
				(width 0.1)
				(type default)
			)
			(layer "F.Fab")
		)
		(pad "1" smd rect
			(at 0 0 90)
			(size 0.508 0.508)
			(layers "F.Cu" "F.Mask" "F.Paste")
			(net "PVCCIO_CPU1")
		)
		(pad "2" smd rect
			(at 0 0.889 90)
			(size 0.508 0.508)
			(layers "F.Cu" "F.Mask" "F.Paste")
			(net "H_CPU1_BMCINIT")
		)
		(zone
			(layer "F.Cu")
			(hatch none 0.5)
			(connect_pads
				(clearance 0)
			)
			(min_thickness 0.25)
			(keepout
				(tracks allowed)
				(vias not_allowed)
				(pads allowed)
				(copperpour not_allowed)
				(footprints allowed)
			)
			(placement
				(enabled no)
				(sheetname "")
			)
			(fill
				(thermal_gap 0.5)
				(thermal_bridge_width 0.5)
				(island_removal_mode 0)
			)
			(polygon
				(pts
					(xy 116.5606 -72.771) (xy 116.5606 -73.279) (xy 116.9416 -73.279) (xy 116.9416 -72.771)
				)
			)
		)
		(zone
			(layer "F.Cu")
			(hatch none 0.5)
			(connect_pads
				(clearance 0)
			)
			(min_thickness 0.25)
			(keepout
				(tracks not_allowed)
				(vias allowed)
				(pads allowed)
				(copperpour not_allowed)
				(footprints allowed)
			)
			(placement
				(enabled no)
				(sheetname "")
			)
			(fill
				(thermal_gap 0.5)
				(thermal_bridge_width 0.5)
				(island_removal_mode 0)
			)
			(polygon
				(pts
					(xy 116.9416 -72.771) (xy 116.9416 -73.279) (xy 116.5606 -73.279) (xy 116.5606 -72.771)
				)
			)
		)
	)
	(footprint ""
		(layer "F.Cu")
		(at 29.083 -76.454 -90)
		(property "Reference" "C1D23"
			(at 0 0 270)
			(layer "F.SilkS")
			(hide yes)
			(effects
				(font
					(size 1.27 1.27)
				)
			)
		)
		(property "Value" ""
			(at 0 0 270)
			(layer "F.Fab")
			(effects
				(font
					(size 1.27 1.27)
				)
			)
		)
		(duplicate_pad_numbers_are_jumpers no)
		(fp_rect
			(start 0.3048 -0.1016)
			(end -0.3048 0.9906)
			(stroke
				(width 0)
				(type default)
			)
			(fill no)
			(layer "F.CrtYd")
		)
		(fp_line
			(start -0.3048 0.9906)
			(end 0.3048 0.9906)
			(stroke
				(width 0.1)
				(type default)
			)
			(layer "F.Fab")
		)
		(fp_line
			(start 0.3048 0.9906)
			(end 0.3048 -0.1016)
			(stroke
				(width 0.1)
				(type default)
			)
			(layer "F.Fab")
		)
		(fp_line
			(start -0.3048 -0.1016)
			(end -0.3048 0.9906)
			(stroke
				(width 0.1)
				(type default)
			)
			(layer "F.Fab")
		)
		(fp_line
			(start 0.3048 -0.1016)
			(end -0.3048 -0.1016)
			(stroke
				(width 0.1)
				(type default)
			)
			(layer "F.Fab")
		)
		(pad "1" smd rect
			(at 0 0 270)
			(size 0.508 0.508)
			(layers "F.Cu" "F.Mask" "F.Paste")
			(net "VR_FET_SW_P12V_STBY_PVCCIN_CPU1")
		)
		(pad "2" smd rect
			(at 0 0.889 270)
			(size 0.508 0.508)
			(layers "F.Cu" "F.Mask" "F.Paste")
			(net "GND")
		)
		(zone
			(layer "F.Cu")
			(hatch none 0.5)
			(connect_pads
				(clearance 0)
			)
			(min_thickness 0.25)
			(keepout
				(tracks allowed)
				(vias not_allowed)
				(pads allowed)
				(copperpour not_allowed)
				(footprints allowed)
			)
			(placement
				(enabled no)
				(sheetname "")
			)
			(fill
				(thermal_gap 0.5)
				(thermal_bridge_width 0.5)
				(island_removal_mode 0)
			)
			(polygon
				(pts
					(xy 28.829 -76.2) (xy 28.829 -76.708) (xy 28.448 -76.708) (xy 28.448 -76.2)
				)
			)
		)
		(zone
			(layer "F.Cu")
			(hatch none 0.5)
			(connect_pads
				(clearance 0)
			)
			(min_thickness 0.25)
			(keepout
				(tracks not_allowed)
				(vias allowed)
				(pads allowed)
				(copperpour not_allowed)
				(footprints allowed)
			)
			(placement
				(enabled no)
				(sheetname "")
			)
			(fill
				(thermal_gap 0.5)
				(thermal_bridge_width 0.5)
				(island_removal_mode 0)
			)
			(polygon
				(pts
					(xy 28.829 -76.2) (xy 28.829 -76.708) (xy 28.448 -76.708) (xy 28.448 -76.2)
				)
			)
		)
	)
	(footprint ""
		(layer "F.Cu")
		(at 467.106 -129.413 180)
		(property "Reference" "R9B13"
			(at 0 0 180)
			(layer "F.SilkS")
			(hide yes)
			(effects
				(font
					(size 1.27 1.27)
				)
			)
		)
		(property "Value" ""
			(at 0 0 180)
			(layer "F.Fab")
			(effects
				(font
					(size 1.27 1.27)
				)
			)
		)
		(duplicate_pad_numbers_are_jumpers no)
		(fp_poly
			(pts
				(xy -0.2794 -0.1016) (xy 0.2794 -0.1016) (xy 0.2794 0.9906) (xy -0.2794 0.9906)
			)
			(stroke
				(width 0)
				(type default)
			)
			(fill no)
			(layer "F.CrtYd")
		)
		(fp_line
			(start 0.2794 0.9906)
			(end 0.2794 -0.1016)
			(stroke
				(width 0.1)
				(type default)
			)
			(layer "F.Fab")
		)
		(fp_line
			(start 0.2794 -0.1016)
			(end -0.2794 -0.1016)
			(stroke
				(width 0.1)
				(type default)
			)
			(layer "F.Fab")
		)
		(fp_line
			(start -0.2794 0.9906)
			(end 0.2794 0.9906)
			(stroke
				(width 0.1)
				(type default)
			)
			(layer "F.Fab")
		)
		(fp_line
			(start -0.2794 -0.1016)
			(end -0.2794 0.9906)
			(stroke
				(width 0.1)
				(type default)
			)
			(layer "F.Fab")
		)
		(pad "1" smd rect
			(at 0 0 180)
			(size 0.508 0.508)
			(layers "F.Cu" "F.Mask" "F.Paste")
			(net "JTAG_MCP_TMS")
		)
		(pad "2" smd rect
			(at 0 0.889 180)
			(size 0.508 0.508)
			(layers "F.Cu" "F.Mask" "F.Paste")
			(net "JTAG_MCP_TMS_R")
		)
		(zone
			(layer "F.Cu")
			(hatch none 0.5)
			(connect_pads
				(clearance 0)
			)
			(min_thickness 0.25)
			(keepout
				(tracks not_allowed)
				(vias allowed)
				(pads allowed)
				(copperpour not_allowed)
				(footprints allowed)
			)
			(placement
				(enabled no)
				(sheetname "")
			)
			(fill
				(thermal_gap 0.5)
				(thermal_bridge_width 0.5)
				(island_removal_mode 0)
			)
			(polygon
				(pts
					(xy 467.36 -130.048) (xy 466.852 -130.048) (xy 466.852 -129.667) (xy 467.36 -129.667)
				)
			)
		)
		(zone
			(layer "F.Cu")
			(hatch none 0.5)
			(connect_pads
				(clearance 0)
			)
			(min_thickness 0.25)
			(keepout
				(tracks allowed)
				(vias not_allowed)
				(pads allowed)
				(copperpour not_allowed)
				(footprints allowed)
			)
			(placement
				(enabled no)
				(sheetname "")
			)
			(fill
				(thermal_gap 0.5)
				(thermal_bridge_width 0.5)
				(island_removal_mode 0)
			)
			(polygon
				(pts
					(xy 467.36 -129.667) (xy 466.852 -129.667) (xy 466.852 -130.048) (xy 467.36 -130.048)
				)
			)
		)
	)
	(footprint ""
		(layer "F.Cu")
		(at 260.697472 -77.636116)
		(property "Reference" "C5D26"
			(at 0 0 0)
			(layer "F.SilkS")
			(hide yes)
			(effects
				(font
					(size 1.27 1.27)
				)
			)
		)
		(property "Value" ""
			(at 0 0 0)
			(layer "F.Fab")
			(effects
				(font
					(size 1.27 1.27)
				)
			)
		)
		(duplicate_pad_numbers_are_jumpers no)
		(fp_poly
			(pts
				(xy -0.4953 -0.2032) (xy 0.4953 -0.2032) (xy 0.4953 1.6002) (xy -0.4953 1.6002)
			)
			(stroke
				(width 0)
				(type default)
			)
			(fill no)
			(layer "F.CrtYd")
		)
		(fp_line
			(start -0.4953 -0.2032)
			(end 0.4953 -0.2032)
			(stroke
				(width 0.1)
				(type default)
			)
			(layer "F.Fab")
		)
		(fp_line
			(start -0.4953 1.6002)
			(end -0.4953 -0.2032)
			(stroke
				(width 0.1)
				(type default)
			)
			(layer "F.Fab")
		)
		(fp_line
			(start 0.4953 -0.2032)
			(end 0.4953 1.6002)
			(stroke
				(width 0.1)
				(type default)
			)
			(layer "F.Fab")
		)
		(fp_line
			(start 0.4953 1.6002)
			(end -0.4953 1.6002)
			(stroke
				(width 0.1)
				(type default)
			)
			(layer "F.Fab")
		)
		(pad "1" smd rect
			(at 0 0)
			(size 0.762 0.889)
			(layers "F.Cu" "F.Mask" "F.Paste")
			(net "PVCCIN_CPU0")
		)
		(pad "2" smd rect
			(at 0 1.397)
			(size 0.762 0.889)
			(layers "F.Cu" "F.Mask" "F.Paste")
			(net "GND")
		)
		(zone
			(layer "F.Cu")
			(hatch none 0.5)
			(connect_pads
				(clearance 0)
			)
			(min_thickness 0.25)
			(keepout
				(tracks not_allowed)
				(vias allowed)
				(pads allowed)
				(copperpour not_allowed)
				(footprints allowed)
			)
			(placement
				(enabled no)
				(sheetname "")
			)
			(fill
				(thermal_gap 0.5)
				(thermal_bridge_width 0.5)
				(island_removal_mode 0)
			)
			(polygon
				(pts
					(xy 260.316472 -77.191616) (xy 261.078472 -77.191616) (xy 261.078472 -76.683616) (xy 260.316472 -76.683616)
				)
			)
		)
	)
	(footprint ""
		(layer "F.Cu")
		(at 18.288 -100.33)
		(property "Reference" "R1C13"
			(at 0 0 0)
			(layer "F.SilkS")
			(hide yes)
			(effects
				(font
					(size 1.27 1.27)
				)
			)
		)
		(property "Value" ""
			(at 0 0 0)
			(layer "F.Fab")
			(effects
				(font
					(size 1.27 1.27)
				)
			)
		)
		(duplicate_pad_numbers_are_jumpers no)
		(fp_rect
			(start -0.2794 -0.1016)
			(end 0.2794 0.9906)
			(stroke
				(width 0)
				(type default)
			)
			(fill no)
			(layer "F.CrtYd")
		)
		(fp_line
			(start -0.2794 -0.1016)
			(end -0.2794 0.9906)
			(stroke
				(width 0.1)
				(type default)
			)
			(layer "F.Fab")
		)
		(fp_line
			(start -0.2794 0.9906)
			(end 0.2794 0.9906)
			(stroke
				(width 0.1)
				(type default)
			)
			(layer "F.Fab")
		)
		(fp_line
			(start 0.2794 -0.1016)
			(end -0.2794 -0.1016)
			(stroke
				(width 0.1)
				(type default)
			)
			(layer "F.Fab")
		)
		(fp_line
			(start 0.2794 0.9906)
			(end 0.2794 -0.1016)
			(stroke
				(width 0.1)
				(type default)
			)
			(layer "F.Fab")
		)
		(pad "1" smd rect
			(at 0 0)
			(size 0.508 0.508)
			(layers "F.Cu" "F.Mask" "F.Paste")
			(net "VR_FET_SW_P12V_STBY_PVCCIN_CPU1")
		)
		(pad "2" smd rect
			(at 0 0.889)
			(size 0.508 0.508)
			(layers "F.Cu" "F.Mask" "F.Paste")
			(net "VR_PVCCIN_CPU1_AVINSEN")
		)
		(zone
			(layer "F.Cu")
			(hatch none 0.5)
			(connect_pads
				(clearance 0)
			)
			(min_thickness 0.25)
			(keepout
				(tracks not_allowed)
				(vias allowed)
				(pads allowed)
				(copperpour not_allowed)
				(footprints allowed)
			)
			(placement
				(enabled no)
				(sheetname "")
			)
			(fill
				(thermal_gap 0.5)
				(thermal_bridge_width 0.5)
				(island_removal_mode 0)
			)
			(polygon
				(pts
					(xy 18.034 -100.076) (xy 18.034 -99.695) (xy 18.542 -99.695) (xy 18.542 -100.076)
				)
			)
		)
		(zone
			(layer "F.Cu")
			(hatch none 0.5)
			(connect_pads
				(clearance 0)
			)
			(min_thickness 0.25)
			(keepout
				(tracks allowed)
				(vias not_allowed)
				(pads allowed)
				(copperpour not_allowed)
				(footprints allowed)
			)
			(placement
				(enabled no)
				(sheetname "")
			)
			(fill
				(thermal_gap 0.5)
				(thermal_bridge_width 0.5)
				(island_removal_mode 0)
			)
			(polygon
				(pts
					(xy 18.034 -100.076) (xy 18.034 -99.695) (xy 18.542 -99.695) (xy 18.542 -100.076)
				)
			)
		)
	)
	(footprint ""
		(layer "F.Cu")
		(at 95.69704 -73.318116)
		(property "Reference" "C2D32"
			(at 0 0 0)
			(layer "F.SilkS")
			(hide yes)
			(effects
				(font
					(size 1.27 1.27)
				)
			)
		)
		(property "Value" ""
			(at 0 0 0)
			(layer "F.Fab")
			(effects
				(font
					(size 1.27 1.27)
				)
			)
		)
		(duplicate_pad_numbers_are_jumpers no)
		(fp_poly
			(pts
				(xy -0.4953 -0.2032) (xy 0.4953 -0.2032) (xy 0.4953 1.6002) (xy -0.4953 1.6002)
			)
			(stroke
				(width 0)
				(type default)
			)
			(fill no)
			(layer "F.CrtYd")
		)
		(fp_line
			(start -0.4953 -0.2032)
			(end 0.4953 -0.2032)
			(stroke
				(width 0.1)
				(type default)
			)
			(layer "F.Fab")
		)
		(fp_line
			(start -0.4953 1.6002)
			(end -0.4953 -0.2032)
			(stroke
				(width 0.1)
				(type default)
			)
			(layer "F.Fab")
		)
		(fp_line
			(start 0.4953 -0.2032)
			(end 0.4953 1.6002)
			(stroke
				(width 0.1)
				(type default)
			)
			(layer "F.Fab")
		)
		(fp_line
			(start 0.4953 1.6002)
			(end -0.4953 1.6002)
			(stroke
				(width 0.1)
				(type default)
			)
			(layer "F.Fab")
		)
		(pad "1" smd rect
			(at 0 0)
			(size 0.762 0.889)
			(layers "F.Cu" "F.Mask" "F.Paste")
			(net "PVCCIN_CPU1")
		)
		(pad "2" smd rect
			(at 0 1.397)
			(size 0.762 0.889)
			(layers "F.Cu" "F.Mask" "F.Paste")
			(net "GND")
		)
		(zone
			(layer "F.Cu")
			(hatch none 0.5)
			(connect_pads
				(clearance 0)
			)
			(min_thickness 0.25)
			(keepout
				(tracks not_allowed)
				(vias allowed)
				(pads allowed)
				(copperpour not_allowed)
				(footprints allowed)
			)
			(placement
				(enabled no)
				(sheetname "")
			)
			(fill
				(thermal_gap 0.5)
				(thermal_bridge_width 0.5)
				(island_removal_mode 0)
			)
			(polygon
				(pts
					(xy 95.31604 -72.873616) (xy 96.07804 -72.873616) (xy 96.07804 -72.365616) (xy 95.31604 -72.365616)
				)
			)
		)
	)
	(footprint ""
		(layer "F.Cu")
		(at 26.924 -3.766312)
		(property "Reference" "C1G18"
			(at 0 0 0)
			(layer "F.SilkS")
			(hide yes)
			(effects
				(font
					(size 1.27 1.27)
				)
			)
		)
		(property "Value" ""
			(at 0 0 0)
			(layer "F.Fab")
			(effects
				(font
					(size 1.27 1.27)
				)
			)
		)
		(duplicate_pad_numbers_are_jumpers no)
		(fp_poly
			(pts
				(xy 0.3048 -0.1016) (xy 0.3048 0.9906) (xy -0.3048 0.9906) (xy -0.3048 -0.1016)
			)
			(stroke
				(width 0)
				(type default)
			)
			(fill no)
			(layer "F.CrtYd")
		)
		(fp_line
			(start -0.3048 -0.1016)
			(end -0.3048 0.9906)
			(stroke
				(width 0.1)
				(type default)
			)
			(layer "F.Fab")
		)
		(fp_line
			(start -0.3048 0.9906)
			(end 0.3048 0.9906)
			(stroke
				(width 0.1)
				(type default)
			)
			(layer "F.Fab")
		)
		(fp_line
			(start 0.3048 -0.1016)
			(end -0.3048 -0.1016)
			(stroke
				(width 0.1)
				(type default)
			)
			(layer "F.Fab")
		)
		(fp_line
			(start 0.3048 0.9906)
			(end 0.3048 -0.1016)
			(stroke
				(width 0.1)
				(type default)
			)
			(layer "F.Fab")
		)
		(pad "1" smd rect
			(at 0 0)
			(size 0.508 0.508)
			(layers "F.Cu" "F.Mask" "F.Paste")
			(net "M_J_CPU_VREF")
		)
		(pad "2" smd rect
			(at 0 0.889)
			(size 0.508 0.508)
			(layers "F.Cu" "F.Mask" "F.Paste")
			(net "GND")
		)
		(zone
			(layer "F.Cu")
			(hatch none 0.5)
			(connect_pads
				(clearance 0)
			)
			(min_thickness 0.25)
			(keepout
				(tracks allowed)
				(vias not_allowed)
				(pads allowed)
				(copperpour not_allowed)
				(footprints allowed)
			)
			(placement
				(enabled no)
				(sheetname "")
			)
			(fill
				(thermal_gap 0.5)
				(thermal_bridge_width 0.5)
				(island_removal_mode 0)
			)
			(polygon
				(pts
					(xy 26.67 -3.512312) (xy 27.178 -3.512312) (xy 27.178 -3.131312) (xy 26.67 -3.131312)
				)
			)
		)
		(zone
			(layer "F.Cu")
			(hatch none 0.5)
			(connect_pads
				(clearance 0)
			)
			(min_thickness 0.25)
			(keepout
				(tracks not_allowed)
				(vias allowed)
				(pads allowed)
				(copperpour not_allowed)
				(footprints allowed)
			)
			(placement
				(enabled no)
				(sheetname "")
			)
			(fill
				(thermal_gap 0.5)
				(thermal_bridge_width 0.5)
				(island_removal_mode 0)
			)
			(polygon
				(pts
					(xy 26.67 -3.131312) (xy 27.178 -3.131312) (xy 27.178 -3.512312) (xy 26.67 -3.512312)
				)
			)
		)
	)
)
